# TIMECARD (Time Appliance Project (Time Card)) — schematic netlist excerpt (pin names and nets, part order shuffled) for the footprints in the layout excerpt that follows; sources: Cadence DE-HDL packaged netlist, KiCad conversion of R4006-B0001-02_R01.brd

R126  RESISTOR  49.9OHM 1%  pkg SMC_0402R_H016  page 23 : \1\ = BF_SMA2_SIG_IO_CONN ; \2\ = SMA2_SIG_IO_CONN

(kicad_pcb
	(version 20260206)
	(generator "pcbnew")
	(generator_version "10.0")
	(general
		(thickness 1.6)
		(legacy_teardrops no)
	)
	(paper "A4")
	(title_block
		(title "timecard-production-celestica-r4006 — R4006-B0001-02_R01.brd")
		(comment 1 "Time Appliance Project (Time Card) / footprints 55-55 of 1113")
	)
	(layers
		(0 "F.Cu" signal "TOP")
		(4 "In1.Cu" signal "L02_GND1")
		(6 "In2.Cu" signal "L03_SIG1")
		(8 "In3.Cu" signal "L04_GND2")
		(10 "In4.Cu" signal "L05_VCC1")
		(12 "In5.Cu" signal "L06_VCC2")
		(14 "In6.Cu" signal "L07_GND3")
		(16 "In7.Cu" signal "L08_SIG2")
		(18 "In8.Cu" signal "L09_GND4")
		(2 "B.Cu" signal "BOTTOM")
		(9 "F.Adhes" user "F.Adhesive")
		(11 "B.Adhes" user "B.Adhesive")
		(13 "F.Paste" user "Package Geometry/Pastemask Top")
		(15 "B.Paste" user "Package Geometry/Pastemask Bottom")
		(5 "F.SilkS" user "Ref Des/Silkscreen Top")
		(7 "B.SilkS" user "Ref Des/Silkscreen Bottom")
		(1 "F.Mask" user "Board Geometry/Soldermask Top")
		(3 "B.Mask" user "Board Geometry/Soldermask Bottom")
		(17 "Dwgs.User" user "User.Drawings")
		(19 "Cmts.User" user "User.Comments")
		(21 "Eco1.User" user "User.Eco1")
		(23 "Eco2.User" user "User.Eco2")
		(25 "Edge.Cuts" user "Board Geometry/Outline")
		(27 "Margin" user)
		(31 "F.CrtYd" user "Package Geometry/Place Bound Top")
		(29 "B.CrtYd" user "Package Geometry/Place Bound Bottom")
		(35 "F.Fab" user "Ref Des/Assembly Top")
		(33 "B.Fab" user "Ref Des/Assembly Bottom")
	)
	(footprint ""
		(layer "F.Cu")
		(at 11.557 -44.704 90)
		(property "Reference" "R126"
			(at 0.508 -1.23063 90)
			(unlocked yes)
			(layer "F.SilkS")
			(effects
				(font
					(size 0.7874 0.5842)
					(thickness 0.1524)
				)
			)
		)
		(property "Value" "VAL*"
			(at 0.02032 2.13233 90)
			(unlocked yes)
			(layer "F.Fab")
			(hide yes)
			(effects
				(font
					(size 0.7874 0.5842)
					(thickness 0.1524)
				)
			)
		)
		(property "Tolerance" "TOL*"
			(at 0.044704 3.05435 90)
			(unlocked yes)
			(layer "Cmts.User")
			(hide yes)
			(effects
				(font
					(size 0.7874 0.5842)
					(thickness 0.1524)
				)
			)
		)
		(property "User Part Number" "PARTNUM*"
			(at 0.02032 4.024884 90)
			(unlocked yes)
			(layer "Cmts.User")
			(hide yes)
			(effects
				(font
					(size 0.7874 0.5842)
					(thickness 0.1524)
				)
			)
		)
		(property "Device Type" "RESISTOR-G155-149R9-01,49.9OHMA"
			(at 0.008382 1.210564 90)
			(unlocked yes)
			(layer "F.Fab")
			(hide yes)
			(effects
				(font
					(size 0.7874 0.5842)
					(thickness 0.1524)
				)
			)
		)
		(duplicate_pad_numbers_are_jumpers no)
		(fp_line
			(start 1.143 -0.5588)
			(end -1.143 -0.5588)
			(stroke
				(width 0.1)
				(type default)
			)
			(layer "F.SilkS")
		)
		(fp_line
			(start -1.143 -0.5588)
			(end -1.143 0.5588)
			(stroke
				(width 0.1)
				(type default)
			)
			(layer "F.SilkS")
		)
		(fp_line
			(start 1.143 0.5588)
			(end 1.143 -0.5588)
			(stroke
				(width 0.1)
				(type default)
			)
			(layer "F.SilkS")
		)
		(fp_line
			(start -1.143 0.5588)
			(end 1.143 0.5588)
			(stroke
				(width 0.1)
				(type default)
			)
			(layer "F.SilkS")
		)
		(fp_poly
			(pts
				(xy -1.143 0.5588) (xy 1.143 0.5588) (xy 1.143 -0.5588) (xy -1.143 -0.5588)
			)
			(stroke
				(width 0)
				(type default)
			)
			(fill no)
			(layer "F.CrtYd")
		)
		(fp_line
			(start 0.508 -0.3048)
			(end -0.508 -0.3048)
			(stroke
				(width 0.1)
				(type default)
			)
			(layer "F.Fab")
		)
		(fp_line
			(start -0.508 -0.3048)
			(end -0.508 0.3048)
			(stroke
				(width 0.1)
				(type default)
			)
			(layer "F.Fab")
		)
		(fp_line
			(start 0.508 0.3048)
			(end 0.508 -0.3048)
			(stroke
				(width 0.1)
				(type default)
			)
			(layer "F.Fab")
		)
		(fp_line
			(start -0.508 0.3048)
			(end 0.508 0.3048)
			(stroke
				(width 0.1)
				(type default)
			)
			(layer "F.Fab")
		)
		(pad "1" smd rect
			(at -0.5334 0 90)
			(size 0.7112 0.6096)
			(layers "F.Cu" "F.Mask" "F.Paste")
			(net "BF_SMA2_SIG_IO_CONN")
		)
		(pad "2" smd rect
			(at 0.5334 0 90)
			(size 0.7112 0.6096)
			(layers "F.Cu" "F.Mask" "F.Paste")
			(net "SMA2_SIG_IO_CONN")
		)
		(zone
			(layer "F.Cu")
			(hatch none 0.5)
			(connect_pads
				(clearance 0)
			)
			(min_thickness 0.25)
			(keepout
				(tracks allowed)
				(vias not_allowed)
				(pads allowed)
				(copperpour not_allowed)
				(footprints allowed)
			)
			(placement
				(enabled no)
				(sheetname "")
			)
			(fill
				(thermal_gap 0.5)
				(thermal_bridge_width 0.5)
				(island_removal_mode 0)
			)
			(polygon
				(pts
					(xy 11.8618 -44.6278) (xy 11.8618 -44.7802) (xy 11.2522 -44.7802) (xy 11.2522 -44.6278)
				)
			)
		)
		(zone
			(layer "F.Cu")
			(hatch none 0.5)
			(connect_pads
				(clearance 0)
			)
			(min_thickness 0.25)
			(keepout
				(tracks not_allowed)
				(vias allowed)
				(pads allowed)
				(copperpour not_allowed)
				(footprints allowed)
			)
			(placement
				(enabled no)
				(sheetname "")
			)
			(fill
				(thermal_gap 0.5)
				(thermal_bridge_width 0.5)
				(island_removal_mode 0)
			)
			(polygon
				(pts
					(xy 11.8618 -44.6278) (xy 11.8618 -44.7802) (xy 11.2522 -44.7802) (xy 11.2522 -44.6278)
				)
			)
		)
	)
)
